(kicad_pcb
	(version 20260206)
	(generator "pcbnew")
	(generator_version "10.0")
	(general
		(thickness 1.6)
		(legacy_teardrops no)
	)
	(paper "A4")
	(title_block
		(title "03242023_DA0F0TMBIJ0_F0T_Motherboard_J_brd_V01_OCP.brd")
		(comment 1 "Grand Teton / footprints 3463-3469 of 6105")
	)
	(layers
		(0 "F.Cu" signal "TOP")
		(4 "In1.Cu" signal "GND")
		(6 "In2.Cu" signal "IN1")
		(8 "In3.Cu" signal "GND1")
		(10 "In4.Cu" signal "IN2")
		(12 "In5.Cu" signal "GND2")
		(14 "In6.Cu" signal "IN3")
		(16 "In7.Cu" signal "GND3")
		(18 "In8.Cu" signal "VCC")
		(20 "In9.Cu" signal "VCC1")
		(22 "In10.Cu" signal "GND4")
		(24 "In11.Cu" signal "IN4")
		(26 "In12.Cu" signal "GND5")
		(28 "In13.Cu" signal "IN5")
		(30 "In14.Cu" signal "GND6")
		(32 "In15.Cu" signal "IN6")
		(34 "In16.Cu" signal "GND7")
		(2 "B.Cu" signal "BOTTOM")
		(9 "F.Adhes" user "F.Adhesive")
		(11 "B.Adhes" user "B.Adhesive")
		(13 "F.Paste" user "Package Geometry/Pastemask Top")
		(15 "B.Paste" user "Package Geometry/Pastemask Bottom")
		(5 "F.SilkS" user "Ref Des/Silkscreen Top")
		(7 "B.SilkS" user "Ref Des/Silkscreen Bottom")
		(1 "F.Mask" user "Board Geometry/Soldermask Top")
		(3 "B.Mask" user "Board Geometry/Soldermask Bottom")
		(17 "Dwgs.User" user "User.Drawings")
		(19 "Cmts.User" user "User.Comments")
		(21 "Eco1.User" user "User.Eco1")
		(23 "Eco2.User" user "User.Eco2")
		(25 "Edge.Cuts" user "Board Geometry/Outline")
		(27 "Margin" user)
		(31 "F.CrtYd" user "Package Geometry/Place Bound Top")
		(29 "B.CrtYd" user "Package Geometry/Place Bound Bottom")
		(35 "F.Fab" user "Ref Des/Assembly Top")
		(33 "B.Fab" user "Ref Des/Assembly Bottom")
	)
	(footprint ""
		(layer "F.Cu")
		(at 136.3853 -112.363504)
		(property "Reference" "R4755"
			(at 0 0 0)
			(layer "F.SilkS")
			(hide yes)
			(effects
				(font
					(size 1.27 1.27)
				)
			)
		)
		(property "Value" ""
			(at 0 0 0)
			(layer "F.Fab")
			(effects
				(font
					(size 1.27 1.27)
				)
			)
		)
		(duplicate_pad_numbers_are_jumpers no)
		(fp_line
			(start -0.7874 -0.4064)
			(end 0.7874 -0.4064)
			(stroke
				(width 0.1524)
				(type default)
			)
			(layer "F.SilkS")
		)
		(fp_line
			(start -0.7874 0.4064)
			(end -0.7874 -0.4064)
			(stroke
				(width 0.1524)
				(type default)
			)
			(layer "F.SilkS")
		)
		(fp_line
			(start 0.7874 -0.4064)
			(end 0.7874 0.4064)
			(stroke
				(width 0.1524)
				(type default)
			)
			(layer "F.SilkS")
		)
		(fp_line
			(start 0.7874 0.4064)
			(end -0.7874 0.4064)
			(stroke
				(width 0.1524)
				(type default)
			)
			(layer "F.SilkS")
		)
		(fp_line
			(start -0.67945 -0.305054)
			(end -0.12065 -0.305054)
			(stroke
				(width 0.1)
				(type default)
			)
			(layer "F.Fab")
		)
		(fp_line
			(start -0.67945 0.3048)
			(end -0.67945 -0.305054)
			(stroke
				(width 0.1)
				(type default)
			)
			(layer "F.Fab")
		)
		(fp_line
			(start -0.12065 -0.305054)
			(end -0.12065 -0.2794)
			(stroke
				(width 0.1)
				(type default)
			)
			(layer "F.Fab")
		)
		(fp_line
			(start -0.12065 -0.2794)
			(end 0.12065 -0.2794)
			(stroke
				(width 0.1)
				(type default)
			)
			(layer "F.Fab")
		)
		(fp_line
			(start -0.12065 0.2794)
			(end -0.12065 0.3048)
			(stroke
				(width 0.1)
				(type default)
			)
			(layer "F.Fab")
		)
		(fp_line
			(start -0.12065 0.3048)
			(end -0.67945 0.3048)
			(stroke
				(width 0.1)
				(type default)
			)
			(layer "F.Fab")
		)
		(fp_line
			(start 0.120396 0.2794)
			(end -0.12065 0.2794)
			(stroke
				(width 0.1)
				(type default)
			)
			(layer "F.Fab")
		)
		(fp_line
			(start 0.120396 0.3048)
			(end 0.120396 0.2794)
			(stroke
				(width 0.1)
				(type default)
			)
			(layer "F.Fab")
		)
		(fp_line
			(start 0.12065 -0.3048)
			(end 0.67945 -0.3048)
			(stroke
				(width 0.1)
				(type default)
			)
			(layer "F.Fab")
		)
		(fp_line
			(start 0.12065 -0.2794)
			(end 0.12065 -0.3048)
			(stroke
				(width 0.1)
				(type default)
			)
			(layer "F.Fab")
		)
		(fp_line
			(start 0.67945 -0.3048)
			(end 0.67945 0.3048)
			(stroke
				(width 0.1)
				(type default)
			)
			(layer "F.Fab")
		)
		(fp_line
			(start 0.67945 0.3048)
			(end 0.120396 0.3048)
			(stroke
				(width 0.1)
				(type default)
			)
			(layer "F.Fab")
		)
		(pad "1" smd circle
			(at -0.40005 0)
			(size 0 0)
			(layers "F.Cu" "F.Mask" "F.Paste")
			(net "OCP_V3_2_AUX_PWR_PLD_EN")
		)
		(pad "2" smd circle
			(at 0.40005 0)
			(size 0 0)
			(layers "F.Cu" "F.Mask" "F.Paste")
			(net "OCP_V3_2_AUX_PWR_PLD_EN_R")
		)
	)
	(footprint ""
		(layer "F.Cu")
		(at 172.033184 -344.7796 -90)
		(property "Reference" "PL18"
			(at -1.768348 -4.904486 90)
			(unlocked yes)
			(layer "F.SilkS")
			(effects
				(font
					(size 0.7874 0.5842)
					(thickness 0.1524)
				)
				(justify left)
			)
		)
		(property "Value" ""
			(at 0 0 270)
			(layer "F.Fab")
			(effects
				(font
					(size 1.27 1.27)
				)
			)
		)
		(duplicate_pad_numbers_are_jumpers no)
		(fp_line
			(start -4.99999 3.750056)
			(end -4.99999 2.2479)
			(stroke
				(width 0.1524)
				(type default)
			)
			(layer "F.SilkS")
		)
		(fp_line
			(start 0 3.750056)
			(end -4.99999 3.750056)
			(stroke
				(width 0.1524)
				(type default)
			)
			(layer "F.SilkS")
		)
		(fp_line
			(start 4.99999 3.750056)
			(end 0 3.750056)
			(stroke
				(width 0.1524)
				(type default)
			)
			(layer "F.SilkS")
		)
		(fp_line
			(start 4.99999 2.2352)
			(end 4.99999 3.750056)
			(stroke
				(width 0.1524)
				(type default)
			)
			(layer "F.SilkS")
		)
		(fp_line
			(start -4.99999 -2.2479)
			(end -4.99999 -3.750056)
			(stroke
				(width 0.1524)
				(type default)
			)
			(layer "F.SilkS")
		)
		(fp_line
			(start -4.99999 -3.750056)
			(end 4.99999 -3.750056)
			(stroke
				(width 0.1524)
				(type default)
			)
			(layer "F.SilkS")
		)
		(fp_line
			(start 4.99999 -3.750056)
			(end 4.99999 -2.2479)
			(stroke
				(width 0.1524)
				(type default)
			)
			(layer "F.SilkS")
		)
		(fp_line
			(start -4.99999 3.750056)
			(end -4.99999 -3.750056)
			(stroke
				(width 0.1)
				(type default)
			)
			(layer "F.Fab")
		)
		(fp_line
			(start 0 3.750056)
			(end -4.99999 3.750056)
			(stroke
				(width 0.1)
				(type default)
			)
			(layer "F.Fab")
		)
		(fp_line
			(start 4.99999 3.750056)
			(end 0 3.750056)
			(stroke
				(width 0.1)
				(type default)
			)
			(layer "F.Fab")
		)
		(fp_line
			(start -4.99999 -3.750056)
			(end 4.99999 -3.750056)
			(stroke
				(width 0.1)
				(type default)
			)
			(layer "F.Fab")
		)
		(fp_line
			(start 4.99999 -3.750056)
			(end 4.99999 3.750056)
			(stroke
				(width 0.1)
				(type default)
			)
			(layer "F.Fab")
		)
		(pad "1" smd rect
			(at -3.299968 0 270)
			(size 3.302 4.2164)
			(layers "F.Cu" "F.Mask" "F.Paste")
			(net "SW_PVCCFA_EHV_FIVRA_CPU1_SW1")
		)
		(pad "2" smd rect
			(at 3.299968 0 270)
			(size 3.302 4.2164)
			(layers "F.Cu" "F.Mask" "F.Paste")
			(net "PVCCFA_EHV_FIVRA_CPU1")
		)
	)
	(footprint ""
		(layer "F.Cu")
		(at 365.46663 -238.162338 90)
		(property "Reference" "C416"
			(at 0 0 90)
			(layer "F.SilkS")
			(hide yes)
			(effects
				(font
					(size 1.27 1.27)
				)
			)
		)
		(property "Value" ""
			(at 0 0 90)
			(layer "F.Fab")
			(effects
				(font
					(size 1.27 1.27)
				)
			)
		)
		(duplicate_pad_numbers_are_jumpers no)
		(fp_line
			(start 0.7874 -0.4064)
			(end 0.7874 0.4064)
			(stroke
				(width 0.1524)
				(type default)
			)
			(layer "F.SilkS")
		)
		(fp_line
			(start -0.7874 -0.4064)
			(end 0.7874 -0.4064)
			(stroke
				(width 0.1524)
				(type default)
			)
			(layer "F.SilkS")
		)
		(fp_line
			(start 0.7874 0.4064)
			(end -0.7874 0.4064)
			(stroke
				(width 0.1524)
				(type default)
			)
			(layer "F.SilkS")
		)
		(fp_line
			(start -0.7874 0.4064)
			(end -0.7874 -0.4064)
			(stroke
				(width 0.1524)
				(type default)
			)
			(layer "F.SilkS")
		)
		(fp_line
			(start -0.12065 -0.305054)
			(end -0.12065 -0.2794)
			(stroke
				(width 0.1)
				(type default)
			)
			(layer "F.Fab")
		)
		(fp_line
			(start -0.67945 -0.305054)
			(end -0.12065 -0.305054)
			(stroke
				(width 0.1)
				(type default)
			)
			(layer "F.Fab")
		)
		(fp_line
			(start 0.67945 -0.3048)
			(end 0.67945 0.3048)
			(stroke
				(width 0.1)
				(type default)
			)
			(layer "F.Fab")
		)
		(fp_line
			(start 0.12065 -0.3048)
			(end 0.67945 -0.3048)
			(stroke
				(width 0.1)
				(type default)
			)
			(layer "F.Fab")
		)
		(fp_line
			(start 0.12065 -0.2794)
			(end 0.12065 -0.3048)
			(stroke
				(width 0.1)
				(type default)
			)
			(layer "F.Fab")
		)
		(fp_line
			(start -0.12065 -0.2794)
			(end 0.12065 -0.2794)
			(stroke
				(width 0.1)
				(type default)
			)
			(layer "F.Fab")
		)
		(fp_line
			(start 0.120396 0.2794)
			(end -0.12065 0.2794)
			(stroke
				(width 0.1)
				(type default)
			)
			(layer "F.Fab")
		)
		(fp_line
			(start -0.12065 0.2794)
			(end -0.12065 0.3048)
			(stroke
				(width 0.1)
				(type default)
			)
			(layer "F.Fab")
		)
		(fp_line
			(start 0.67945 0.3048)
			(end 0.120396 0.3048)
			(stroke
				(width 0.1)
				(type default)
			)
			(layer "F.Fab")
		)
		(fp_line
			(start 0.120396 0.3048)
			(end 0.120396 0.2794)
			(stroke
				(width 0.1)
				(type default)
			)
			(layer "F.Fab")
		)
		(fp_line
			(start -0.12065 0.3048)
			(end -0.67945 0.3048)
			(stroke
				(width 0.1)
				(type default)
			)
			(layer "F.Fab")
		)
		(fp_line
			(start -0.67945 0.3048)
			(end -0.67945 -0.305054)
			(stroke
				(width 0.1)
				(type default)
			)
			(layer "F.Fab")
		)
		(pad "1" smd circle
			(at -0.40005 0 90)
			(size 0 0)
			(layers "F.Cu" "F.Mask" "F.Paste")
			(net "PVCCINFAON_CPU0")
		)
		(pad "2" smd circle
			(at 0.40005 0 90)
			(size 0 0)
			(layers "F.Cu" "F.Mask" "F.Paste")
			(net "GND")
		)
	)
	(footprint ""
		(layer "F.Cu")
		(at 436.08625 -16.248126 -90)
		(property "Reference" "R419"
			(at 0 0 270)
			(layer "F.SilkS")
			(hide yes)
			(effects
				(font
					(size 1.27 1.27)
				)
			)
		)
		(property "Value" ""
			(at 0 0 270)
			(layer "F.Fab")
			(effects
				(font
					(size 1.27 1.27)
				)
			)
		)
		(duplicate_pad_numbers_are_jumpers no)
		(fp_line
			(start -0.7874 0.4064)
			(end -0.7874 -0.4064)
			(stroke
				(width 0.1524)
				(type default)
			)
			(layer "F.SilkS")
		)
		(fp_line
			(start 0.7874 0.4064)
			(end -0.7874 0.4064)
			(stroke
				(width 0.1524)
				(type default)
			)
			(layer "F.SilkS")
		)
		(fp_line
			(start -0.7874 -0.4064)
			(end 0.7874 -0.4064)
			(stroke
				(width 0.1524)
				(type default)
			)
			(layer "F.SilkS")
		)
		(fp_line
			(start 0.7874 -0.4064)
			(end 0.7874 0.4064)
			(stroke
				(width 0.1524)
				(type default)
			)
			(layer "F.SilkS")
		)
		(fp_line
			(start -0.67945 0.3048)
			(end -0.67945 -0.305054)
			(stroke
				(width 0.1)
				(type default)
			)
			(layer "F.Fab")
		)
		(fp_line
			(start -0.12065 0.3048)
			(end -0.67945 0.3048)
			(stroke
				(width 0.1)
				(type default)
			)
			(layer "F.Fab")
		)
		(fp_line
			(start 0.120396 0.3048)
			(end 0.120396 0.2794)
			(stroke
				(width 0.1)
				(type default)
			)
			(layer "F.Fab")
		)
		(fp_line
			(start 0.67945 0.3048)
			(end 0.120396 0.3048)
			(stroke
				(width 0.1)
				(type default)
			)
			(layer "F.Fab")
		)
		(fp_line
			(start -0.12065 0.2794)
			(end -0.12065 0.3048)
			(stroke
				(width 0.1)
				(type default)
			)
			(layer "F.Fab")
		)
		(fp_line
			(start 0.120396 0.2794)
			(end -0.12065 0.2794)
			(stroke
				(width 0.1)
				(type default)
			)
			(layer "F.Fab")
		)
		(fp_line
			(start -0.12065 -0.2794)
			(end 0.12065 -0.2794)
			(stroke
				(width 0.1)
				(type default)
			)
			(layer "F.Fab")
		)
		(fp_line
			(start 0.12065 -0.2794)
			(end 0.12065 -0.3048)
			(stroke
				(width 0.1)
				(type default)
			)
			(layer "F.Fab")
		)
		(fp_line
			(start 0.12065 -0.3048)
			(end 0.67945 -0.3048)
			(stroke
				(width 0.1)
				(type default)
			)
			(layer "F.Fab")
		)
		(fp_line
			(start 0.67945 -0.3048)
			(end 0.67945 0.3048)
			(stroke
				(width 0.1)
				(type default)
			)
			(layer "F.Fab")
		)
		(fp_line
			(start -0.67945 -0.305054)
			(end -0.12065 -0.305054)
			(stroke
				(width 0.1)
				(type default)
			)
			(layer "F.Fab")
		)
		(fp_line
			(start -0.12065 -0.305054)
			(end -0.12065 -0.2794)
			(stroke
				(width 0.1)
				(type default)
			)
			(layer "F.Fab")
		)
		(pad "1" smd circle
			(at -0.40005 0 270)
			(size 0 0)
			(layers "F.Cu" "F.Mask" "F.Paste")
			(net "RST_OCP_V3_1_BUF_N")
		)
		(pad "2" smd circle
			(at 0.40005 0 270)
			(size 0 0)
			(layers "F.Cu" "F.Mask" "F.Paste")
			(net "RST_PERST0_OCP_SFF_N")
		)
	)
	(footprint ""
		(layer "F.Cu")
		(at 20.014184 -112.314482)
		(property "Reference" "L16"
			(at 0 0 0)
			(layer "F.SilkS")
			(hide yes)
			(effects
				(font
					(size 1.27 1.27)
				)
			)
		)
		(property "Value" ""
			(at 0 0 0)
			(layer "F.Fab")
			(effects
				(font
					(size 1.27 1.27)
				)
			)
		)
		(duplicate_pad_numbers_are_jumpers no)
		(fp_line
			(start -1.27 -0.5842)
			(end 1.27 -0.5842)
			(stroke
				(width 0.1524)
				(type default)
			)
			(layer "F.SilkS")
		)
		(fp_line
			(start -1.27 -0.5588)
			(end -1.27 -0.5842)
			(stroke
				(width 0.1524)
				(type default)
			)
			(layer "F.SilkS")
		)
		(fp_line
			(start -1.27 0.5842)
			(end -1.27 -0.5842)
			(stroke
				(width 0.1524)
				(type default)
			)
			(layer "F.SilkS")
		)
		(fp_line
			(start -0.127 0.5842)
			(end -0.127 -0.5842)
			(stroke
				(width 0.1524)
				(type default)
			)
			(layer "F.SilkS")
		)
		(fp_line
			(start 0.127 0.5842)
			(end 0.127 -0.5842)
			(stroke
				(width 0.1524)
				(type default)
			)
			(layer "F.SilkS")
		)
		(fp_line
			(start 1.27 0.5842)
			(end -1.27 0.5842)
			(stroke
				(width 0.1524)
				(type default)
			)
			(layer "F.SilkS")
		)
		(fp_line
			(start 1.27 0.5842)
			(end 1.27 -0.5842)
			(stroke
				(width 0.1524)
				(type default)
			)
			(layer "F.SilkS")
		)
		(fp_line
			(start -1.194308 -0.406654)
			(end -0.9144 -0.406654)
			(stroke
				(width 0.1)
				(type default)
			)
			(layer "F.Fab")
		)
		(fp_line
			(start -1.194308 0.406654)
			(end -1.194308 -0.406654)
			(stroke
				(width 0.1)
				(type default)
			)
			(layer "F.Fab")
		)
		(fp_line
			(start -0.9144 -0.508)
			(end 0.9144 -0.508)
			(stroke
				(width 0.1)
				(type default)
			)
			(layer "F.Fab")
		)
		(fp_line
			(start -0.9144 -0.406654)
			(end -0.9144 -0.508)
			(stroke
				(width 0.1)
				(type default)
			)
			(layer "F.Fab")
		)
		(fp_line
			(start -0.9144 0.406654)
			(end -1.194308 0.406654)
			(stroke
				(width 0.1)
				(type default)
			)
			(layer "F.Fab")
		)
		(fp_line
			(start -0.9144 0.508)
			(end -0.9144 0.406654)
			(stroke
				(width 0.1)
				(type default)
			)
			(layer "F.Fab")
		)
		(fp_line
			(start 0.9144 -0.508)
			(end 0.9144 -0.406654)
			(stroke
				(width 0.1)
				(type default)
			)
			(layer "F.Fab")
		)
		(fp_line
			(start 0.9144 -0.406654)
			(end 1.1938 -0.406654)
			(stroke
				(width 0.1)
				(type default)
			)
			(layer "F.Fab")
		)
		(fp_line
			(start 0.9144 0.4064)
			(end 0.9144 0.508)
			(stroke
				(width 0.1)
				(type default)
			)
			(layer "F.Fab")
		)
		(fp_line
			(start 0.9144 0.508)
			(end -0.9144 0.508)
			(stroke
				(width 0.1)
				(type default)
			)
			(layer "F.Fab")
		)
		(fp_line
			(start 1.1938 -0.406654)
			(end 1.1938 0.4064)
			(stroke
				(width 0.1)
				(type default)
			)
			(layer "F.Fab")
		)
		(fp_line
			(start 1.1938 0.4064)
			(end 0.9144 0.4064)
			(stroke
				(width 0.1)
				(type default)
			)
			(layer "F.Fab")
		)
		(pad "1" smd rect
			(at -0.7366 0 270)
			(size 0.7112 0.8128)
			(layers "F.Cu" "F.Mask" "F.Paste")
			(net "P3V3_AUX")
		)
		(pad "2" smd rect
			(at 0.7366 0 270)
			(size 0.7112 0.8128)
			(layers "F.Cu" "F.Mask" "F.Paste")
			(net "P3V3_ADC128_VCC")
		)
	)
	(footprint ""
		(layer "F.Cu")
		(at 395.413738 -150.09241 -90)
		(property "Reference" "C569"
			(at 0 0 270)
			(layer "F.SilkS")
			(hide yes)
			(effects
				(font
					(size 1.27 1.27)
				)
			)
		)
		(property "Value" ""
			(at 0 0 270)
			(layer "F.Fab")
			(effects
				(font
					(size 1.27 1.27)
				)
			)
		)
		(duplicate_pad_numbers_are_jumpers no)
		(fp_line
			(start -0.7874 0.4064)
			(end -0.7874 -0.4064)
			(stroke
				(width 0.1524)
				(type default)
			)
			(layer "F.SilkS")
		)
		(fp_line
			(start 0.7874 0.4064)
			(end -0.7874 0.4064)
			(stroke
				(width 0.1524)
				(type default)
			)
			(layer "F.SilkS")
		)
		(fp_line
			(start -0.7874 -0.4064)
			(end 0.7874 -0.4064)
			(stroke
				(width 0.1524)
				(type default)
			)
			(layer "F.SilkS")
		)
		(fp_line
			(start 0.7874 -0.4064)
			(end 0.7874 0.4064)
			(stroke
				(width 0.1524)
				(type default)
			)
			(layer "F.SilkS")
		)
		(fp_line
			(start -0.67945 0.3048)
			(end -0.67945 -0.305054)
			(stroke
				(width 0.1)
				(type default)
			)
			(layer "F.Fab")
		)
		(fp_line
			(start -0.12065 0.3048)
			(end -0.67945 0.3048)
			(stroke
				(width 0.1)
				(type default)
			)
			(layer "F.Fab")
		)
		(fp_line
			(start 0.120396 0.3048)
			(end 0.120396 0.2794)
			(stroke
				(width 0.1)
				(type default)
			)
			(layer "F.Fab")
		)
		(fp_line
			(start 0.67945 0.3048)
			(end 0.120396 0.3048)
			(stroke
				(width 0.1)
				(type default)
			)
			(layer "F.Fab")
		)
		(fp_line
			(start -0.12065 0.2794)
			(end -0.12065 0.3048)
			(stroke
				(width 0.1)
				(type default)
			)
			(layer "F.Fab")
		)
		(fp_line
			(start 0.120396 0.2794)
			(end -0.12065 0.2794)
			(stroke
				(width 0.1)
				(type default)
			)
			(layer "F.Fab")
		)
		(fp_line
			(start -0.12065 -0.2794)
			(end 0.12065 -0.2794)
			(stroke
				(width 0.1)
				(type default)
			)
			(layer "F.Fab")
		)
		(fp_line
			(start 0.12065 -0.2794)
			(end 0.12065 -0.3048)
			(stroke
				(width 0.1)
				(type default)
			)
			(layer "F.Fab")
		)
		(fp_line
			(start 0.12065 -0.3048)
			(end 0.67945 -0.3048)
			(stroke
				(width 0.1)
				(type default)
			)
			(layer "F.Fab")
		)
		(fp_line
			(start 0.67945 -0.3048)
			(end 0.67945 0.3048)
			(stroke
				(width 0.1)
				(type default)
			)
			(layer "F.Fab")
		)
		(fp_line
			(start -0.67945 -0.305054)
			(end -0.12065 -0.305054)
			(stroke
				(width 0.1)
				(type default)
			)
			(layer "F.Fab")
		)
		(fp_line
			(start -0.12065 -0.305054)
			(end -0.12065 -0.2794)
			(stroke
				(width 0.1)
				(type default)
			)
			(layer "F.Fab")
		)
		(pad "1" smd circle
			(at -0.40005 0 270)
			(size 0 0)
			(layers "F.Cu" "F.Mask" "F.Paste")
			(net "P3V3_AUX")
		)
		(pad "2" smd circle
			(at 0.40005 0 270)
			(size 0 0)
			(layers "F.Cu" "F.Mask" "F.Paste")
			(net "GND")
		)
	)
	(footprint ""
		(layer "F.Cu")
		(at 416.3822 -17.612614 90)
		(property "Reference" "C857"
			(at 0 0 90)
			(layer "F.SilkS")
			(hide yes)
			(effects
				(font
					(size 1.27 1.27)
				)
			)
		)
		(property "Value" ""
			(at 0 0 90)
			(layer "F.Fab")
			(effects
				(font
					(size 1.27 1.27)
				)
			)
		)
		(duplicate_pad_numbers_are_jumpers no)
		(fp_line
			(start 0.299974 -0.150114)
			(end 0.299974 0.150114)
			(stroke
				(width 0.1)
				(type default)
			)
			(layer "F.Fab")
		)
		(fp_line
			(start -0.299974 -0.150114)
			(end 0.299974 -0.150114)
			(stroke
				(width 0.1)
				(type default)
			)
			(layer "F.Fab")
		)
		(fp_line
			(start 0.299974 0.150114)
			(end -0.299974 0.150114)
			(stroke
				(width 0.1)
				(type default)
			)
			(layer "F.Fab")
		)
		(fp_line
			(start -0.299974 0.150114)
			(end -0.299974 -0.150114)
			(stroke
				(width 0.1)
				(type default)
			)
			(layer "F.Fab")
		)
		(pad "1" smd rect
			(at -0.2667 0 90)
			(size 0.3048 0.381)
			(layers "F.Cu" "F.Mask" "F.Paste")
			(net "P5E_CPU0_PE1_TX_C_DP<6>")
		)
		(pad "2" smd rect
			(at 0.2667 0 90)
			(size 0.3048 0.381)
			(layers "F.Cu" "F.Mask" "F.Paste")
			(net "P5E_CPU0_PE1_TX_DP<6>")
		)
	)
)
